# T6G (Grand Teton) — schematic parts with pin connectivity, parts 7442–7599 of 8303; source: Cadence DE-HDL packaged netlist (pstxprt.dat, pstxnet.dat, pstchip.dat)

R6094  Q_RES  0 5% EMPTY  pkg 0402LF  page 80 : 1 = E1S_0_PERST1_CLKREQ_R_N ; 2 = E1S_0_PERST1_CLKREQ_N
R6095  Q_RES  0 5% CHIP  pkg 0402LF  page 80 : 1 = IRQ_HSC_FAULT_BUF_R_N ; 2 = IRQ_HSC_FAULT_BUF_N
R6096  Q_RES  0 5% CHIP  pkg 0402LF  page 80 : 1 = FM_UV_ADR_TRIGGER_R_N ; 2 = FM_UV_ADR_TRIGGER_N
R6097  Q_RES  0 5% CHIP  pkg 0402LF  page 189 : 1 = MB0_P12V_STBY_PWRGD ; 2 = P5V_AUX_EN
R6098  Q_RES  10K 5% EMPTY  pkg 0402LF  page 76 : 1 = GND ; 2 = SPI_CPU0_CLK
R6099  Q_RES  0 5% CHIP  pkg 0402LF  page 190 : 1 = PWRGD_P3V3_AUX_R1 ; 2 = PWRGD_P3V3_AUX
R6100  Q_RES  49.9 1% CHIP  pkg 0402LF  page 34 : 1 = FM_BIOS_POST_CMPLT_BUF_R1_N ; 2 = FM_BIOS_POST_CMPLT_BUF_N
R6101  Q_RES  0 5% CHIP  pkg 0402LF  page 171 : 1 = SCM_JTAG_MUX_S0 ; 2 = SCM_JTAG_MUX_S0_R1
R6102  Q_RES  0 5% CHIP  pkg 0402LF  page 171 : 1 = SCM_JTAG_MUX_S0 ; 2 = SCM_JTAG_MUX_S0_R2
R6103  Q_RES  0 5% CHIP  pkg 0402LF  page 173 : 1 = JTAG_CPUX_TDI_R1 ; 2 = JTAG_CPUX_TDI
R6104  Q_RES  0 5% CHIP  pkg 0402LF  page 174 : 1 = JTAG_CPU0_BYPASS ; 2 = JTAG_CPU0_BYPASS_R1
R6105  Q_RES  0 5% CHIP  pkg 0402LF  page 174 : 1 = JTAG_CPU0_TDO_CPU1_TDI_R1 ; 2 = JTAG_CPU0_TDO_CPU1_TDI
R6106  Q_RES  10K 5% CHIP  pkg 0402LF  page 167 : 1 = PVDD18_S5_P0 ; 2 = FM_PASSWORD_CLEAR_N
R6107  Q_RES  10K 5% CHIP  pkg 0402LF  page 167 : 1 = PVDD18_S5_P0 ; 2 = BIOS_DEBUG_MODE
R6108  Q_RES  0 5% CHIP  pkg 0402LF  page 172 : 1 = HDT_HDR_TDO ; 2 = HDT_HDR_TDO_R
R6109  Q_RES  0 5% CHIP  pkg 0402LF  page 173 : 1 = JTAG_TDO ; 2 = JTAG_TDO_R
R6110  Q_RES  0 5% CHIP  pkg 0402LF  page 174 : 1 = JTAG_CPUX_TDO_R ; 2 = JTAG_CPUX_TDO
R6111  Q_RES  0 5% CHIP  pkg 0402LF  page 172 : 1 = JTAG_TDO_R1 ; 2 = JTAG_TDO
R6112  Q_RES  33.2 1% CHIP  pkg 0402LF  page 85 : 1 = RST_PERST_CPU0_SWB_N ; 2 = RST_PERST_CPU0_SWB_R_N
R6113  Q_RES  33.2 1% CHIP  pkg 0402LF  page 85 : 1 = RST_PERST_CPU1_SWB_N ; 2 = RST_PERST_CPU1_SWB_R_N
R6114  Q_RES  2K 1% CHIP  pkg 0402LF  page 83 : 1 = RST_PERST_CPU0_SWB_N ; 2 = GND
R6115  Q_RES  2K 1% CHIP  pkg 0402LF  page 83 : 1 = RST_PERST_CPU1_SWB_N ; 2 = GND
R6116  Q_RES  0 5% CHIP  pkg 0402LF  page 80 : 1 = E1S_0_PERST1_CLKREQ_R_N ; 2 = E1S_0_PRSNT_N
R6117  Q_RES  100 1% CHIP  pkg 0402LF  page 80 : 1 = HP_LVC3_OCP_V3_2_PRSNT2_PLD_N ; 2 = PRSNT_OCP_V3_2_N
R6118  Q_RES  0 5% CHIP  pkg 0402LF  page 85 : 1 = PWRGD_P5V_AUX_R3 ; 2 = PWRGD_P5V_AUX_R2
R6119  Q_RES  0 5% CHIP  pkg 0402LF  page 269 : 1 = PWRGD_P3V3_AUX ; 2 = P1V8_AUX_ENABLE
R6120  Q_RES  1K 1% CHIP  pkg 0402LF  page 84 : 1 = PVDD18_S5_P0 ; 2 = FM_BOARD_SKU_ID4
R6121  Q_RES  1K 1% EMPTY  pkg 0402LF  page 84 : 1 = PVDD18_S5_P0 ; 2 = FM_BOARD_SKU_ID3
R6122  Q_RES  1K 1% EMPTY  pkg 0402LF  page 84 : 1 = PVDD18_S5_P0 ; 2 = FM_BOARD_SKU_ID2
R6123  Q_RES  1K 1% EMPTY  pkg 0402LF  page 84 : 1 = PVDD18_S5_P0 ; 2 = FM_BOARD_SKU_ID1
R6124  Q_RES  1K 1% EMPTY  pkg 0402LF  page 84 : 1 = PVDD18_S5_P0 ; 2 = FM_BOARD_SKU_ID0
R6125  Q_RES  1K 1% EMPTY  pkg 0402LF  page 84 : 1 = FM_BOARD_SKU_ID4 ; 2 = GND
R6126  Q_RES  1K 1% CHIP  pkg 0402LF  page 84 : 1 = FM_BOARD_SKU_ID3 ; 2 = GND
R6127  Q_RES  1K 1% CHIP  pkg 0402LF  page 84 : 1 = FM_BOARD_SKU_ID2 ; 2 = GND
R6128  Q_RES  1K 1% CHIP  pkg 0402LF  page 84 : 1 = FM_BOARD_SKU_ID1 ; 2 = GND
R6129  Q_RES  1K 1% CHIP  pkg 0402LF  page 84 : 1 = FM_BOARD_SKU_ID0 ; 2 = GND
R6130  Q_RES  1K 1% CHIP  pkg 0402LF  page 84 : 1 = PVDD18_S5_P0 ; 2 = FAB_REV_ID2
R6131  Q_RES  1K 1% EMPTY  pkg 0402LF  page 84 : 1 = PVDD18_S5_P0 ; 2 = FAB_REV_ID1
R6132  Q_RES  1K 1% EMPTY  pkg 0402LF  page 84 : 1 = PVDD18_S5_P0 ; 2 = FAB_REV_ID0
R6133  Q_RES  1K 1% EMPTY  pkg 0402LF  page 84 : 1 = FAB_REV_ID2 ; 2 = GND
R6134  Q_RES  1K 1% CHIP  pkg 0402LF  page 84 : 1 = FAB_REV_ID1 ; 2 = GND
R6135  Q_RES  1K 1% CHIP  pkg 0402LF  page 84 : 1 = FAB_REV_ID0 ; 2 = GND
R6136  Q_RES  1K 1% CHIP  pkg 0402LF  page 84 : 1 = P3V3_AUX ; 2 = FM_BOARD_BMC_SKU_ID4
R6137  Q_RES  1K 1% EMPTY  pkg 0402LF  page 84 : 1 = P3V3_AUX ; 2 = FM_BOARD_BMC_SKU_ID3
R6138  Q_RES  1K 1% EMPTY  pkg 0402LF  page 84 : 1 = P3V3_AUX ; 2 = FM_BOARD_BMC_SKU_ID2
R6139  Q_RES  1K 1% EMPTY  pkg 0402LF  page 84 : 1 = P3V3_AUX ; 2 = FM_BOARD_BMC_SKU_ID1
R6140  Q_RES  1K 1% EMPTY  pkg 0402LF  page 84 : 1 = P3V3_AUX ; 2 = FM_BOARD_BMC_SKU_ID0
R6141  Q_RES  1K 1% EMPTY  pkg 0402LF  page 84 : 1 = FM_BOARD_BMC_SKU_ID4 ; 2 = GND
R6142  Q_RES  1K 1% CHIP  pkg 0402LF  page 84 : 1 = FM_BOARD_BMC_SKU_ID3 ; 2 = GND
R6143  Q_RES  1K 1% CHIP  pkg 0402LF  page 84 : 1 = FM_BOARD_BMC_SKU_ID2 ; 2 = GND
R6144  Q_RES  1K 1% CHIP  pkg 0402LF  page 84 : 1 = FM_BOARD_BMC_SKU_ID1 ; 2 = GND
R6145  Q_RES  1K 1% CHIP  pkg 0402LF  page 84 : 1 = FM_BOARD_BMC_SKU_ID0 ; 2 = GND
R6146  Q_RES  1K 1% CHIP  pkg 0402LF  page 84 : 1 = P1V8_AUX ; 2 = FAB_BMC_REV_ID2
R6147  Q_RES  1K 1% EMPTY  pkg 0402LF  page 84 : 1 = P1V8_AUX ; 2 = FAB_BMC_REV_ID1
R6148  Q_RES  1K 1% EMPTY  pkg 0402LF  page 84 : 1 = P1V8_AUX ; 2 = FAB_BMC_REV_ID0
R6149  Q_RES  1K 1% EMPTY  pkg 0402LF  page 84 : 1 = FAB_BMC_REV_ID2 ; 2 = GND
R6150  Q_RES  1K 1% CHIP  pkg 0402LF  page 84 : 1 = FAB_BMC_REV_ID1 ; 2 = GND
R6151  Q_RES  1K 1% CHIP  pkg 0402LF  page 84 : 1 = FAB_BMC_REV_ID0 ; 2 = GND
R6152  Q_RES  0 5% CHIP  pkg 0201LF  page 113 : 1 = P2E_MB_BMC_TX_C_DP<0> ; 2 = P2E_MB_BMC_TX_C_R1_DP<0>
R6153  Q_RES  0 5% CHIP  pkg 0201LF  page 113 : 1 = P2E_MB_BMC_TX_C_DN<0> ; 2 = P2E_MB_BMC_TX_C_R1_DN<0>
R6154  Q_RES  0 5% CHIP  pkg 0201LF  page 113 : 1 = P2E_MB_BMC_TX_C_DP<0> ; 2 = P2E_MB_BMC_TX_C_R2_DP<0>
R6155  Q_RES  0 5% CHIP  pkg 0201LF  page 113 : 1 = P2E_MB_BMC_TX_C_DN<0> ; 2 = P2E_MB_BMC_TX_C_R2_DN<0>
R6156  Q_RES  0 5% CHIP  pkg 0201LF  page 113 : 1 = P2E_MB_BMC_RX_DP<0> ; 2 = P2E_MB_BMC_RX_R1_DP<0>
R6157  Q_RES  0 5% CHIP  pkg 0201LF  page 113 : 1 = P2E_MB_BMC_RX_DN<0> ; 2 = P2E_MB_BMC_RX_R1_DN<0>
R6158  Q_RES  0 5% CHIP  pkg 0201LF  page 113 : 1 = P2E_MB_BMC_RX_DP<0> ; 2 = P2E_MB_BMC_RX_R2_DP<0>
R6159  Q_RES  0 5% CHIP  pkg 0201LF  page 113 : 1 = P2E_MB_BMC_RX_DN<0> ; 2 = P2E_MB_BMC_RX_R2_DN<0>
R6160  Q_RES  1K 1% CHIP  pkg 0402LF  page 112 : 1 = PD_P2E_BUF2_ENSMB ; 2 = GND
R6162  Q_RES  0 5% CHIP  pkg 0402LF  page 112 : 1 = FM_P2E_EN2_N ; 2 = CLK_GEN2_GPU_FPGA_OE_OR_N
R6163  Q_RES  1K 1% EMPTY  pkg 0402LF  page 112 : 1 = P3V3_AUX ; 2 = FM_P2E_BUF2_EQB1
R6164  Q_RES  1K 1% CHIP  pkg 0402LF  page 112 : 1 = FM_P2E_BUF2_EQB1 ; 2 = GND
R6165  Q_RES  1K 1% EMPTY  pkg 0402LF  page 112 : 1 = P3V3_AUX ; 2 = FM_P2E_BUF2_EQB0
R6166  Q_RES  1K 1% EMPTY  pkg 0402LF  page 112 : 1 = FM_P2E_BUF2_EQB0 ; 2 = GND
R6167  Q_RES  1K 1% EMPTY  pkg 0402LF  page 112 : 1 = P3V3_AUX ; 2 = FM_P2E_BUF2_VODB_DB
R6168  Q_RES  1K 1% CHIP  pkg 0402LF  page 112 : 1 = FM_P2E_BUF2_VODB_DB ; 2 = GND
R6169  Q_RES  1K 1% EMPTY  pkg 0402LF  page 112 : 1 = P3V3_AUX ; 2 = FM_P2E_BUF2_VODA_DB
R6170  Q_RES  1K 1% CHIP  pkg 0402LF  page 112 : 1 = FM_P2E_BUF2_VODA_DB ; 2 = GND
R6171  Q_RES  1K 1% EMPTY  pkg 0402LF  page 112 : 1 = P3V3_AUX ; 2 = FM_P2E_BUF2_EQA1
R6172  Q_RES  1K 1% CHIP  pkg 0402LF  page 112 : 1 = FM_P2E_BUF2_EQA1 ; 2 = GND
R6173  Q_RES  1K 1% EMPTY  pkg 0402LF  page 112 : 1 = P3V3_AUX ; 2 = FM_P2E_BUF2_EQA0
R6174  Q_RES  1K 1% EMPTY  pkg 0402LF  page 112 : 1 = FM_P2E_BUF2_EQA0 ; 2 = GND
R6175  Q_RES  1K 1% EMPTY  pkg 0402LF  page 112 : 1 = P3V3_AUX ; 2 = FM_P2E_BUF2_RXDET
R6176  Q_RES  1K 1% EMPTY  pkg 0402LF  page 112 : 1 = FM_P2E_BUF2_RXDET ; 2 = GND
R6177  Q_RES  1K 1% CHIP  pkg 0402LF  page 112 : 1 = P3V3_AUX ; 2 = FM_P2E_BUF2_SD_TH
R6178  Q_RES  1K 1% EMPTY  pkg 0402LF  page 112 : 1 = FM_P2E_BUF2_SD_TH ; 2 = GND
R6179  Q_RES  1K 1% CHIP  pkg 0402LF  page 112 : 1 = P3V3_AUX ; 2 = FM_P2E_BUF2_VOD_SEL
R6180  Q_RES  1K 1% EMPTY  pkg 0402LF  page 112 : 1 = FM_P2E_BUF2_VOD_SEL ; 2 = GND
R6181  Q_RES  4.7K 5% CHIP  pkg 0402LF  page 171 : 1 = P3V3_AUX ; 2 = PU_U212_EN_N
R6182  Q_RES  4.7K 5% CHIP  pkg 0402LF  page 171 : 1 = P3V3_AUX ; 2 = PU_U160_EN_N
R6183  Q_RES  0 5% CHIP  pkg 0402LF  page 82 : 1 = FM_SEC_MUX_OE_N ; 2 = FM_SEC_MUX_OE_R_N
R6184  Q_RES  0 5% CHIP  pkg 0402LF  page 82 : 1 = FM_SEC_MUX_SEL ; 2 = FM_SEC_MUX_R_SEL
R6185  Q_RES  10K 1% CHIP  pkg 0402LF  page 83 : 1 = FM_SEC_MUX_OE_N ; 2 = GND
R6186  Q_RES  4.7K 5% EMPTY  pkg 0402LF  page 83 : 1 = FM_SEC_MUX_OE_N ; 2 = P3V3_AUX
R6187  Q_RES  10K 1% EMPTY  pkg 0402LF  page 83 : 1 = FM_SEC_MUX_SEL ; 2 = GND
R6188  Q_RES  4.7K 5% EMPTY  pkg 0402LF  page 83 : 1 = FM_SEC_MUX_SEL ; 2 = P3V3_AUX
R6190  Q_RES  0 5% CHIP  pkg 0201LF  page 180 : 1 = USB2_CPU0_P0_DP ; 2 = USB2_CPU0_P0_R1_DP
R6191  Q_RES  0 5% CHIP  pkg 0201LF  page 180 : 1 = USB2_CPU0_P0_DN ; 2 = USB2_CPU0_P0_R1_DN
R6192  Q_RES  0 5% CHIP  pkg 0201LF  page 180 : 1 = USB2_CPU0_P0_DP ; 2 = USB2_CPU0_P0_R2_DP
R6193  Q_RES  0 5% CHIP  pkg 0201LF  page 180 : 1 = USB2_CPU0_P0_DN ; 2 = USB2_CPU0_P0_R2_DN
R6194  Q_RES  0 5% CHIP  pkg 0201LF  page 180 : 1 = USB2_CPU0_P0_HUB1_R_DP ; 2 = USB2_HUB_EXT_DP
R6195  Q_RES  0 5% CHIP  pkg 0201LF  page 180 : 1 = USB2_CPU0_P0_HUB1_R_DN ; 2 = USB2_HUB_EXT_DN
R6196  Q_RES  0 5% CHIP  pkg 0201LF  page 180 : 1 = USB2_CPU0_P0_HUB2_R_DP ; 2 = USB2_HUB_EXT_DP
R6197  Q_RES  0 5% CHIP  pkg 0201LF  page 180 : 1 = USB2_CPU0_P0_HUB2_R_DN ; 2 = USB2_HUB_EXT_DN
R6200  Q_RES  0 5% CHIP  pkg 0402LF  page 250 : 1 = SMB_USB_CPU0_HUB1_SDA_R ; 2 = SMB_USB_CPU0_HUB1_SDA
R6201  Q_RES  0 5% CHIP  pkg 0402LF  page 250 : 1 = SMB_USB_CPU0_HUB1_SCL_R ; 2 = SMB_USB_CPU0_HUB1_SCL
R6202  Q_RES  200 1% CHIP  pkg 0402LF  page 176 : 1 = GND ; 2 = USB_CPU0_HUB1_RREF_SS
R6203  Q_RES  6.04K 1% CHIP  pkg 0402LF  page 176 : 1 = GND ; 2 = USB_CPU0_HUB1_RREF_USB2
R6204  Q_RES  10K 1% CHIP  pkg 0402LF  page 176 : 1 = P3V3_AUX ; 2 = PU_CPU0_USB_HUB_PWR_EN
R6205  Q_RES  10K 1% CHIP  pkg 0402LF  page 176 : 1 = P3V3_AUX ; 2 = PU_CPU0_USB_HUB_OVRCURR
R6206  Q_RES  10K 1% CHIP  pkg 0402LF  page 176 : 1 = P3V3_AUX ; 2 = PU_CPU0_USB_HUB_RESERVED2
R6207  Q_RES  10K 1% CHIP  pkg 0402LF  page 176 : 1 = P3V3_AUX ; 2 = PU_CPU0_USB_HUB_RESERVED1
R6208  Q_RES  10K 1% CHIP  pkg 0402LF  page 176 : 1 = P5V_AUX ; 2 = USB_CPU0_HUB1_VBUS_US
R6209  Q_RES  10K 1% CHIP  pkg 0402LF  page 176 : 1 = USB_CPU0_HUB1_VBUS_US ; 2 = GND
R6210  Q_RES  0 5% CHIP  pkg 0402LF  page 267 : 1 = HSC_CSOUT ; 2 = HSC_D_OC
R6211  Q_RES  2.2K 5% CHIP  pkg 0402LF  page 250 : 1 = P3V3_AUX ; 2 = SMB_USB_CPU0_HUB1_SCL
R6212  Q_RES  2.2K 5% CHIP  pkg 0402LF  page 250 : 1 = P3V3_AUX ; 2 = SMB_USB_CPU0_HUB1_SDA
R6213  Q_RES  10K 1% CHIP  pkg 0402LF  page 176 : 1 = P3V3_AUX ; 2 = USB_CPU0_HUB1_MODE_SEL1
R6214  Q_RES  10K 1% EMPTY  pkg 0402LF  page 176 : 1 = USB_CPU0_HUB1_MODE_SEL1 ; 2 = GND
R6215  Q_RES  10K 1% CHIP  pkg 0402LF  page 176 : 1 = P3V3_AUX ; 2 = USB_CPU0_HUB1_MODE_SEL0
R6216  Q_RES  10K 1% EMPTY  pkg 0402LF  page 176 : 1 = USB_CPU0_HUB1_MODE_SEL0 ; 2 = GND
R6217  Q_RES  10K 1% EMPTY  pkg 0402LF  page 176 : 1 = USB_CPU0_ADD_A0 ; 2 = GND
R6218  Q_RES  10K 1% EMPTY  pkg 0402LF  page 176 : 1 = P3V3_AUX ; 2 = USB_CPU0_ADD_A1
R6219  Q_RES  10K 1% CHIP  pkg 0402LF  page 176 : 1 = USB_CPU0_ADD_A1 ; 2 = GND
R6220  Q_RES  10K 1% EMPTY  pkg 0402LF  page 176 : 1 = P3V3_AUX ; 2 = USB_CPU0_ADD_A2
R6221  Q_RES  10K 1% CHIP  pkg 0402LF  page 176 : 1 = USB_CPU0_ADD_A2 ; 2 = GND
R6222  Q_RES  10K 1% CHIP  pkg 0402LF  page 176 : 1 = P3V3_AUX ; 2 = USB_CPU0_ADD_A0
R6223  Q_RES  1K 1% CHIP  pkg 0402LF  page 176 : 1 = PD_USB_CPU0_WP ; 2 = GND
R6224  Q_RES  33.2 1% EMPTY  pkg 0402LF  page 176 : 1 = SMB_USB_CPU0_HUB1_SCL ; 2 = SMB_USB_CPU0_HUB1_SCL_R2
R6225  Q_RES  33.2 1% EMPTY  pkg 0402LF  page 176 : 1 = SMB_USB_CPU0_HUB1_SDA ; 2 = SMB_USB_CPU0_HUB1_SDA_R2
R6226  Q_RES  10K 1% EMPTY  pkg 0402LF  page 176 : 1 = P3V3_AUX ; 2 = SMB_USB_CPU0_HUB1_SCL_R2
R6227  Q_RES  10K 1% EMPTY  pkg 0402LF  page 176 : 1 = P3V3_AUX ; 2 = SMB_USB_CPU0_HUB1_SDA_R2
R6228  Q_RES  0 5% CHIP  pkg 0402LF  page 252 : 1 = SMB_P12V_HSC_SDA_R ; 2 = SMB_P12V_HSC_SDA
R6229  Q_RES  0 5% CHIP  pkg 0402LF  page 252 : 1 = SMB_P12V_HSC_SCL_R ; 2 = SMB_P12V_HSC_SCL
R6230  Q_RES  2.2K 5% CHIP  pkg 0402LF  page 267 : 1 = P3V3_AUX ; 2 = SMB_P12V_HSC_SDA
R6231  Q_RES  2.2K 5% CHIP  pkg 0402LF  page 267 : 1 = P3V3_AUX ; 2 = SMB_P12V_HSC_SCL
R6232  Q_RES  160K 1% EMPTY  pkg 0402LF  page 267 : 1 = HSC_CSOUT ; 2 = A_HSC_LOW
R6233  Q_RES  10K 1% EMPTY  pkg 0402LF  page 267 : 1 = A_HSC_LOW ; 2 = GND
R6234  Q_RES  160K 1% EMPTY  pkg 0402LF  page 267 : 1 = HSC_CSOUT ; 2 = A_HSC_HIGH
R6235  Q_RES  10K 1% EMPTY  pkg 0402LF  page 267 : 1 = A_HSC_HIGH ; 2 = GND
R6236  Q_RES  10K 1% EMPTY  pkg 0402LF  page 267 : 1 = P3V3_AUX ; 2 = A_HSC_LOW_GATE
R6237  Q_RES  0 5% EMPTY  pkg 0402LF  page 267 : 1 = A_HSC_LOW_GATE ; 2 = GND
R6238  Q_RES  0 5% EMPTY  pkg 0402LF  page 267 : 1 = A_HSC_LOW_DRAIN ; 2 = HSC_D_OC
R6239  Q_RES  10K 1% CHIP  pkg 0402LF  page 267 : 1 = P3V3_AUX ; 2 = HSC_D_OC
R6240  Q_RES  0 5% CHIP  pkg 0402LF  page 270 : 1 = PWRGD_P1V8_AUX_R ; 2 = P1V2_AUX_ENABLE
R6241  Q_RES  0 5% CHIP  pkg 0402LF  page 270 : 1 = PWRGD_P1V2_AUX ; 2 = PWRGD_P1V2_AUX_R
R6242  Q_RES  0 5% CHIP  pkg 0402LF  page 269 : 1 = P3V3_AUX ; 2 = P1V8_AUX_VCC
R6243  Q_RES  10K 1% CHIP  pkg 0402LF  page 269 : 1 = P3V3_AUX ; 2 = PWRGD_P1V8_AUX
R6244  Q_RES  10K 1% CHIP  pkg 0402LF  page 270 : 1 = P3V3_AUX ; 2 = PWRGD_P1V2_AUX
R6245  Q_RES  0 5% CHIP  pkg 0402LF  page 270 : 1 = P3V3_AUX ; 2 = P1V2_AUX_VCC
R6246  Q_RES  130 1% CHIP  pkg 0402LF  page 254 : 1 = LED_PWRGD_P1V2_AUX ; 2 = P3V3_AUX
R6247  Q_RES  4.7K 1% CHIP  pkg 0402LF  page 271 : 1 = P3V3_AUX ; 2 = HSC_TYPE_ADC_ALERT
R6250  Q_RES  4.7K 1% CHIP  pkg 0402LF  page 271 : 1 = GND ; 2 = HSC_TYPE_ADC_A1
R6251  Q_RES  4.7K 1% EMPTY  pkg 0402LF  page 271 : 1 = GND ; 2 = HSC_TYPE_ADC_A0
R6252  Q_RES  33.2 1% CHIP  pkg 0402LF  page 271 : 1 = SMB_LM75_0_3V3AUX_SCL ; 2 = SMB_HSC_TYPE_ADC_SCL
R6253  Q_RES  33.2 1% CHIP  pkg 0402LF  page 271 : 1 = SMB_LM75_0_3V3AUX_SDA ; 2 = SMB_HSC_TYPE_ADC_SDA
R6254  Q_RES  0 5% CHIP  pkg 0402LF  page 271 : 1 = HSC_TYPE_ADC_A0 ; 2 = SMB_HSC_TYPE_ADC_SDA
R6257  Q_RES  1M 1% CHIP  pkg 0402LF  page 179 : 1 = XTAL_USB_CPU0_HUB2_XOUT ; 2 = XTAL_USB_CPU0_HUB2_XIN
R6258  Q_RES  4.7K 5% EMPTY  pkg 0402LF  page 178 : 1 = P3V3_AUX ; 2 = USB_HUB2_TI_PWRCTL2_MRP_VDD12
R6259  Q_RES  0 5% CHIP  pkg 0402LF  page 178 : 1 = P1V2_CPU0_USB2_DVDD12 ; 2 = USB_HUB2_TI_PWRCTL2_MRP_VDD12
